FILE_TYPE = CONNECTIVITY;
{Allegro Design Entry HDL 17.2-2016 S081 (4005846) 1/11/2022}
"PAGE_NUMBER" = 31;
0"NC";
1"P5E_CPU0_PE4_TX_DP<15:0>";
2"P5E_CPU0_PE4_TX_DN<15:0>";
3"P5E_CPU0_PE4_RX_DP<15:0>";
4"P5E_CPU0_PE4_RX_DN<15:0>";
5"P5E_CPU0_PE4_RX_DN<15>";
6"P5E_CPU0_PE4_RX_DN<14>";
7"P5E_CPU0_PE4_RX_DN<13>";
8"P5E_CPU0_PE4_RX_DN<12>";
9"P5E_CPU0_PE4_RX_DN<11>";
10"P5E_CPU0_PE4_RX_DN<10>";
11"P5E_CPU0_PE4_RX_DN<9>";
12"P5E_CPU0_PE4_RX_DN<8>";
13"P5E_CPU0_PE4_RX_DN<7>";
14"P5E_CPU0_PE4_RX_DN<6>";
15"P5E_CPU0_PE4_RX_DN<5>";
16"P5E_CPU0_PE4_RX_DN<4>";
17"P5E_CPU0_PE4_RX_DN<3>";
18"P5E_CPU0_PE4_RX_DN<2>";
19"P5E_CPU0_PE4_RX_DN<1>";
20"P5E_CPU0_PE4_RX_DN<0>";
21"P5E_CPU0_PE4_RX_DP<15>";
22"P5E_CPU0_PE4_RX_DP<14>";
23"P5E_CPU0_PE4_RX_DP<13>";
24"P5E_CPU0_PE4_RX_DP<12>";
25"P5E_CPU0_PE4_RX_DP<11>";
26"P5E_CPU0_PE4_RX_DP<10>";
27"P5E_CPU0_PE4_RX_DP<9>";
28"P5E_CPU0_PE4_RX_DP<8>";
29"P5E_CPU0_PE4_RX_DP<7>";
30"P5E_CPU0_PE4_RX_DP<6>";
31"P5E_CPU0_PE4_RX_DP<5>";
32"P5E_CPU0_PE4_RX_DP<4>";
33"P5E_CPU0_PE4_RX_DP<3>";
34"P5E_CPU0_PE4_RX_DP<2>";
35"P5E_CPU0_PE4_RX_DP<1>";
36"P5E_CPU0_PE4_RX_DP<0>";
37"P5E_CPU0_PE4_TX_DN<15>";
38"P5E_CPU0_PE4_TX_DN<14>";
39"P5E_CPU0_PE4_TX_DN<13>";
40"P5E_CPU0_PE4_TX_DN<12>";
41"P5E_CPU0_PE4_TX_DN<11>";
42"P5E_CPU0_PE4_TX_DN<10>";
43"P5E_CPU0_PE4_TX_DN<9>";
44"P5E_CPU0_PE4_TX_DN<8>";
45"P5E_CPU0_PE4_TX_DN<7>";
46"P5E_CPU0_PE4_TX_DN<6>";
47"P5E_CPU0_PE4_TX_DN<5>";
48"P5E_CPU0_PE4_TX_DN<4>";
49"P5E_CPU0_PE4_TX_DN<3>";
50"P5E_CPU0_PE4_TX_DN<2>";
51"P5E_CPU0_PE4_TX_DN<1>";
52"P5E_CPU0_PE4_TX_DN<0>";
53"P5E_CPU0_PE4_TX_DP<15>";
54"P5E_CPU0_PE4_TX_DP<14>";
55"P5E_CPU0_PE4_TX_DP<13>";
56"P5E_CPU0_PE4_TX_DP<12>";
57"P5E_CPU0_PE4_TX_DP<11>";
58"P5E_CPU0_PE4_TX_DP<10>";
59"P5E_CPU0_PE4_TX_DP<9>";
60"P5E_CPU0_PE4_TX_DP<8>";
61"P5E_CPU0_PE4_TX_DP<7>";
62"P5E_CPU0_PE4_TX_DP<6>";
63"P5E_CPU0_PE4_TX_DP<5>";
64"P5E_CPU0_PE4_TX_DP<4>";
65"P5E_CPU0_PE4_TX_DP<3>";
66"P5E_CPU0_PE4_TX_DP<2>";
67"P5E_CPU0_PE4_TX_DP<1>";
68"P5E_CPU0_PE4_TX_DP<0>";
%"SOCKET4677_AZIF0045P001C01CS"
"21","(2100,3125)","0","pure_quanta","I139";
;
PART_NUMBER"DGA^7000023"
VALUE"SOCKET4677_AZIF0045-P001C01CS"
MATERIAL"IO"
PART_TYPE"SMLF"
$LOCATION"U2"
CDS_LMAN_SYM_OUTLINE"-1050,950,1050,-950"
NEEDS_NO_SIZE"TRUE"
CDS_LIB"pure_quanta"
CDS_LOCATION"U2"
$SEC"21"
CDS_SEC"21";
"PE4_TX_DP0"
$PN"M87"68;
"PE4_TX_DP1"
$PN"N86"67;
"PE4_TX_DP2"
$PN"T87"66;
"PE4_TX_DP3"
$PN"V85"65;
"PE4_TX_DP4"
$PN"Y87"64;
"PE4_TX_DP5"
$PN"AB85"63;
"PE4_TX_DP6"
$PN"AD87"62;
"PE4_TX_DP7"
$PN"AF85"61;
"PE4_TX_DP8"
$PN"AH87"60;
"PE4_TX_DP9"
$PN"AK85"59;
"PE4_TX_DP10"
$PN"AM87"58;
"PE4_TX_DP11"
$PN"AN86"57;
"PE4_TX_DP12"
$PN"AT87"56;
"PE4_TX_DP13"
$PN"AV85"55;
"PE4_TX_DP14"
$PN"AY87"54;
"PE4_TX_DP15"
$PN"BB85"53;
"PE4_TX_DN0"
$PN"L86"52;
"PE4_TX_DN1"
$PN"P85"51;
"PE4_TX_DN2"
$PN"R86"50;
"PE4_TX_DN3"
$PN"U86"49;
"PE4_TX_DN4"
$PN"W86"48;
"PE4_TX_DN5"
$PN"AA86"47;
"PE4_TX_DN6"
$PN"AC86"46;
"PE4_TX_DN7"
$PN"AE86"45;
"PE4_TX_DN8"
$PN"AG86"44;
"PE4_TX_DN9"
$PN"AJ86"43;
"PE4_TX_DN10"
$PN"AL86"42;
"PE4_TX_DN11"
$PN"AP85"41;
"PE4_TX_DN12"
$PN"AR86"40;
"PE4_TX_DN13"
$PN"AU86"39;
"PE4_TX_DN14"
$PN"AW86"38;
"PE4_TX_DN15"
$PN"BA86"37;
"PE4_RX_DP0"
$PN"K89"36;
"PE4_RX_DP1"
$PN"N90"35;
"PE4_RX_DP2"
$PN"R90"34;
"PE4_RX_DP3"
$PN"U90"33;
"PE4_RX_DP4"
$PN"W90"32;
"PE4_RX_DP5"
$PN"AA90"31;
"PE4_RX_DP6"
$PN"AC90"30;
"PE4_RX_DP7"
$PN"AE90"29;
"PE4_RX_DP8"
$PN"AG90"28;
"PE4_RX_DP9"
$PN"AJ90"27;
"PE4_RX_DP10"
$PN"AL90"26;
"PE4_RX_DP11"
$PN"AN90"25;
"PE4_RX_DP12"
$PN"AR90"24;
"PE4_RX_DP13"
$PN"AU90"23;
"PE4_RX_DP14"
$PN"AW90"22;
"PE4_RX_DP15"
$PN"BA90"21;
"PE4_RX_DN0"
$PN"J90"20;
"PE4_RX_DN1"
$PN"P89"19;
"PE4_RX_DN2"
$PN"T91"18;
"PE4_RX_DN3"
$PN"V89"17;
"PE4_RX_DN4"
$PN"Y91"16;
"PE4_RX_DN5"
$PN"AB89"15;
"PE4_RX_DN6"
$PN"AD91"14;
"PE4_RX_DN7"
$PN"AF89"13;
"PE4_RX_DN8"
$PN"AH91"12;
"PE4_RX_DN9"
$PN"AK89"11;
"PE4_RX_DN10"
$PN"AM91"10;
"PE4_RX_DN11"
$PN"AP89"9;
"PE4_RX_DN12"
$PN"AT91"8;
"PE4_RX_DN13"
$PN"AV89"7;
"PE4_RX_DN14"
$PN"AY91"6;
"PE4_RX_DN15"
$PN"BB89"5;
%"TAP"
"1","(3825,2325)","0","standard","I207";
;
CDS_LIB"standard"
BODY_TYPE"PLUMBING"
HDL_TAP"TRUE";
"B \NAC \NWC"2;
"S \NAC"
BN"0"52;
%"TAP"
"1","(3825,2375)","0","standard","I208";
;
CDS_LIB"standard"
BODY_TYPE"PLUMBING"
HDL_TAP"TRUE";
"B \NAC \NWC"2;
"S \NAC"
BN"1"51;
%"TAP"
"1","(3825,2475)","0","standard","I209";
;
CDS_LIB"standard"
BODY_TYPE"PLUMBING"
HDL_TAP"TRUE";
"B \NAC \NWC"2;
"S \NAC"
BN"3"49;
%"TAP"
"1","(3825,2425)","0","standard","I210";
;
CDS_LIB"standard"
BODY_TYPE"PLUMBING"
HDL_TAP"TRUE";
"B \NAC \NWC"2;
"S \NAC"
BN"2"50;
%"TAP"
"1","(3825,2525)","0","standard","I211";
;
CDS_LIB"standard"
BODY_TYPE"PLUMBING"
HDL_TAP"TRUE";
"B \NAC \NWC"2;
"S \NAC"
BN"4"48;
%"TAP"
"1","(3825,2575)","0","standard","I212";
;
CDS_LIB"standard"
BODY_TYPE"PLUMBING"
HDL_TAP"TRUE";
"B \NAC \NWC"2;
"S \NAC"
BN"5"47;
%"TAP"
"1","(3825,2625)","0","standard","I213";
;
CDS_LIB"standard"
BODY_TYPE"PLUMBING"
HDL_TAP"TRUE";
"B \NAC \NWC"2;
"S \NAC"
BN"6"46;
%"TAP"
"1","(3825,2725)","0","standard","I214";
;
CDS_LIB"standard"
BODY_TYPE"PLUMBING"
HDL_TAP"TRUE";
"B \NAC \NWC"2;
"S \NAC"
BN"8"44;
%"TAP"
"1","(3825,2675)","0","standard","I215";
;
CDS_LIB"standard"
BODY_TYPE"PLUMBING"
HDL_TAP"TRUE";
"B \NAC \NWC"2;
"S \NAC"
BN"7"45;
%"TAP"
"1","(3825,2775)","0","standard","I216";
;
CDS_LIB"standard"
BODY_TYPE"PLUMBING"
HDL_TAP"TRUE";
"B \NAC \NWC"2;
"S \NAC"
BN"9"43;
%"TAP"
"1","(3825,2825)","0","standard","I217";
;
CDS_LIB"standard"
BODY_TYPE"PLUMBING"
HDL_TAP"TRUE";
"B \NAC \NWC"2;
"S \NAC"
BN"10"42;
%"TAP"
"1","(3825,2875)","0","standard","I218";
;
CDS_LIB"standard"
BODY_TYPE"PLUMBING"
HDL_TAP"TRUE";
"B \NAC \NWC"2;
"S \NAC"
BN"11"41;
%"TAP"
"1","(3825,2925)","0","standard","I219";
;
CDS_LIB"standard"
BODY_TYPE"PLUMBING"
HDL_TAP"TRUE";
"B \NAC \NWC"2;
"S \NAC"
BN"12"40;
%"TAP"
"1","(3825,2975)","0","standard","I220";
;
CDS_LIB"standard"
BODY_TYPE"PLUMBING"
HDL_TAP"TRUE";
"B \NAC \NWC"2;
"S \NAC"
BN"13"39;
%"TAP"
"1","(3825,3025)","0","standard","I221";
;
CDS_LIB"standard"
BODY_TYPE"PLUMBING"
HDL_TAP"TRUE";
"B \NAC \NWC"2;
"S \NAC"
BN"14"38;
%"TAP"
"1","(3825,3075)","0","standard","I222";
;
CDS_LIB"standard"
BODY_TYPE"PLUMBING"
HDL_TAP"TRUE";
"B \NAC \NWC"2;
"S \NAC"
BN"15"37;
%"TAP"
"1","(3825,3175)","0","standard","I223";
;
CDS_LIB"standard"
BODY_TYPE"PLUMBING"
HDL_TAP"TRUE";
"B \NAC \NWC"1;
"S \NAC"
BN"0"68;
%"TAP"
"1","(3825,3225)","0","standard","I224";
;
CDS_LIB"standard"
BODY_TYPE"PLUMBING"
HDL_TAP"TRUE";
"B \NAC \NWC"1;
"S \NAC"
BN"1"67;
%"TAP"
"1","(3825,3275)","0","standard","I225";
;
CDS_LIB"standard"
BODY_TYPE"PLUMBING"
HDL_TAP"TRUE";
"B \NAC \NWC"1;
"S \NAC"
BN"2"66;
%"TAP"
"1","(3825,3375)","0","standard","I226";
;
CDS_LIB"standard"
BODY_TYPE"PLUMBING"
HDL_TAP"TRUE";
"B \NAC \NWC"1;
"S \NAC"
BN"4"64;
%"TAP"
"1","(3825,3325)","0","standard","I227";
;
CDS_LIB"standard"
BODY_TYPE"PLUMBING"
HDL_TAP"TRUE";
"B \NAC \NWC"1;
"S \NAC"
BN"3"65;
%"TAP"
"1","(3825,3425)","0","standard","I228";
;
CDS_LIB"standard"
BODY_TYPE"PLUMBING"
HDL_TAP"TRUE";
"B \NAC \NWC"1;
"S \NAC"
BN"5"63;
%"TAP"
"1","(3825,3475)","0","standard","I229";
;
CDS_LIB"standard"
BODY_TYPE"PLUMBING"
HDL_TAP"TRUE";
"B \NAC \NWC"1;
"S \NAC"
BN"6"62;
%"TAP"
"1","(3825,3525)","0","standard","I230";
;
CDS_LIB"standard"
BODY_TYPE"PLUMBING"
HDL_TAP"TRUE";
"B \NAC \NWC"1;
"S \NAC"
BN"7"61;
%"TAP"
"1","(3825,3625)","0","standard","I231";
;
CDS_LIB"standard"
BODY_TYPE"PLUMBING"
HDL_TAP"TRUE";
"B \NAC \NWC"1;
"S \NAC"
BN"9"59;
%"TAP"
"1","(3825,3675)","0","standard","I232";
;
CDS_LIB"standard"
BODY_TYPE"PLUMBING"
HDL_TAP"TRUE";
"B \NAC \NWC"1;
"S \NAC"
BN"10"58;
%"TAP"
"1","(3825,3575)","0","standard","I233";
;
CDS_LIB"standard"
BODY_TYPE"PLUMBING"
HDL_TAP"TRUE";
"B \NAC \NWC"1;
"S \NAC"
BN"8"60;
%"TAP"
"1","(3825,3825)","0","standard","I234";
;
CDS_LIB"standard"
BODY_TYPE"PLUMBING"
HDL_TAP"TRUE";
"B \NAC \NWC"1;
"S \NAC"
BN"13"55;
%"TAP"
"1","(3825,3925)","0","standard","I235";
;
CDS_LIB"standard"
BODY_TYPE"PLUMBING"
HDL_TAP"TRUE";
"B \NAC \NWC"1;
"S \NAC"
BN"15"53;
%"TAP"
"1","(3825,3875)","0","standard","I236";
;
CDS_LIB"standard"
BODY_TYPE"PLUMBING"
HDL_TAP"TRUE";
"B \NAC \NWC"1;
"S \NAC"
BN"14"54;
%"TAP"
"1","(3825,3725)","0","standard","I237";
;
CDS_LIB"standard"
BODY_TYPE"PLUMBING"
HDL_TAP"TRUE";
"B \NAC \NWC"1;
"S \NAC"
BN"11"57;
%"TAP"
"1","(3825,3775)","0","standard","I238";
;
CDS_LIB"standard"
BODY_TYPE"PLUMBING"
HDL_TAP"TRUE";
"B \NAC \NWC"1;
"S \NAC"
BN"12"56;
%"TAP"
"1","(400,2325)","2","standard","I243";
;
CDS_LIB"standard"
BODY_TYPE"PLUMBING"
HDL_TAP"TRUE";
"B \NAC \NWC"4;
"S \NAC"
BN"0"20;
%"TAP"
"1","(400,2375)","2","standard","I244";
;
CDS_LIB"standard"
BODY_TYPE"PLUMBING"
HDL_TAP"TRUE";
"B \NAC \NWC"4;
"S \NAC"
BN"1"19;
%"TAP"
"1","(400,2425)","2","standard","I245";
;
CDS_LIB"standard"
BODY_TYPE"PLUMBING"
HDL_TAP"TRUE";
"B \NAC \NWC"4;
"S \NAC"
BN"2"18;
%"TAP"
"1","(400,2575)","2","standard","I246";
;
CDS_LIB"standard"
BODY_TYPE"PLUMBING"
HDL_TAP"TRUE";
"B \NAC \NWC"4;
"S \NAC"
BN"5"15;
%"TAP"
"1","(400,2525)","2","standard","I247";
;
CDS_LIB"standard"
BODY_TYPE"PLUMBING"
HDL_TAP"TRUE";
"B \NAC \NWC"4;
"S \NAC"
BN"4"16;
%"TAP"
"1","(400,2625)","2","standard","I248";
;
CDS_LIB"standard"
BODY_TYPE"PLUMBING"
HDL_TAP"TRUE";
"B \NAC \NWC"4;
"S \NAC"
BN"6"14;
%"TAP"
"1","(400,2675)","2","standard","I249";
;
CDS_LIB"standard"
BODY_TYPE"PLUMBING"
HDL_TAP"TRUE";
"B \NAC \NWC"4;
"S \NAC"
BN"7"13;
%"TAP"
"1","(400,2725)","2","standard","I250";
;
CDS_LIB"standard"
BODY_TYPE"PLUMBING"
HDL_TAP"TRUE";
"B \NAC \NWC"4;
"S \NAC"
BN"8"12;
%"TAP"
"1","(400,2825)","2","standard","I251";
;
CDS_LIB"standard"
BODY_TYPE"PLUMBING"
HDL_TAP"TRUE";
"B \NAC \NWC"4;
"S \NAC"
BN"10"10;
%"TAP"
"1","(400,2875)","2","standard","I252";
;
CDS_LIB"standard"
BODY_TYPE"PLUMBING"
HDL_TAP"TRUE";
"B \NAC \NWC"4;
"S \NAC"
BN"11"9;
%"TAP"
"1","(400,2775)","2","standard","I253";
;
CDS_LIB"standard"
BODY_TYPE"PLUMBING"
HDL_TAP"TRUE";
"B \NAC \NWC"4;
"S \NAC"
BN"9"11;
%"TAP"
"1","(400,3025)","2","standard","I254";
;
CDS_LIB"standard"
BODY_TYPE"PLUMBING"
HDL_TAP"TRUE";
"B \NAC \NWC"4;
"S \NAC"
BN"14"6;
%"TAP"
"1","(400,3075)","2","standard","I255";
;
CDS_LIB"standard"
BODY_TYPE"PLUMBING"
HDL_TAP"TRUE";
"B \NAC \NWC"4;
"S \NAC"
BN"15"5;
%"TAP"
"1","(400,2975)","2","standard","I256";
;
CDS_LIB"standard"
BODY_TYPE"PLUMBING"
HDL_TAP"TRUE";
"B \NAC \NWC"4;
"S \NAC"
BN"13"7;
%"TAP"
"1","(400,2925)","2","standard","I257";
;
CDS_LIB"standard"
BODY_TYPE"PLUMBING"
HDL_TAP"TRUE";
"B \NAC \NWC"4;
"S \NAC"
BN"12"8;
%"TAP"
"1","(400,3175)","2","standard","I258";
;
CDS_LIB"standard"
BODY_TYPE"PLUMBING"
HDL_TAP"TRUE";
"B \NAC \NWC"3;
"S \NAC"
BN"0"36;
%"TAP"
"1","(400,3225)","2","standard","I259";
;
CDS_LIB"standard"
BODY_TYPE"PLUMBING"
HDL_TAP"TRUE";
"B \NAC \NWC"3;
"S \NAC"
BN"1"35;
%"TAP"
"1","(400,3275)","2","standard","I260";
;
CDS_LIB"standard"
BODY_TYPE"PLUMBING"
HDL_TAP"TRUE";
"B \NAC \NWC"3;
"S \NAC"
BN"2"34;
%"TAP"
"1","(400,3375)","2","standard","I261";
;
CDS_LIB"standard"
BODY_TYPE"PLUMBING"
HDL_TAP"TRUE";
"B \NAC \NWC"3;
"S \NAC"
BN"4"32;
%"TAP"
"1","(400,3325)","2","standard","I262";
;
CDS_LIB"standard"
BODY_TYPE"PLUMBING"
HDL_TAP"TRUE";
"B \NAC \NWC"3;
"S \NAC"
BN"3"33;
%"TAP"
"1","(400,3425)","2","standard","I263";
;
CDS_LIB"standard"
BODY_TYPE"PLUMBING"
HDL_TAP"TRUE";
"B \NAC \NWC"3;
"S \NAC"
BN"5"31;
%"TAP"
"1","(400,3475)","2","standard","I264";
;
CDS_LIB"standard"
BODY_TYPE"PLUMBING"
HDL_TAP"TRUE";
"B \NAC \NWC"3;
"S \NAC"
BN"6"30;
%"TAP"
"1","(400,3525)","2","standard","I265";
;
CDS_LIB"standard"
BODY_TYPE"PLUMBING"
HDL_TAP"TRUE";
"B \NAC \NWC"3;
"S \NAC"
BN"7"29;
%"TAP"
"1","(400,3575)","2","standard","I266";
;
CDS_LIB"standard"
BODY_TYPE"PLUMBING"
HDL_TAP"TRUE";
"B \NAC \NWC"3;
"S \NAC"
BN"8"28;
%"TAP"
"1","(400,3625)","2","standard","I267";
;
CDS_LIB"standard"
BODY_TYPE"PLUMBING"
HDL_TAP"TRUE";
"B \NAC \NWC"3;
"S \NAC"
BN"9"27;
%"TAP"
"1","(400,3675)","2","standard","I268";
;
CDS_LIB"standard"
BODY_TYPE"PLUMBING"
HDL_TAP"TRUE";
"B \NAC \NWC"3;
"S \NAC"
BN"10"26;
%"TAP"
"1","(400,3725)","2","standard","I269";
;
CDS_LIB"standard"
BODY_TYPE"PLUMBING"
HDL_TAP"TRUE";
"B \NAC \NWC"3;
"S \NAC"
BN"11"25;
%"TAP"
"1","(400,3775)","2","standard","I270";
;
CDS_LIB"standard"
BODY_TYPE"PLUMBING"
HDL_TAP"TRUE";
"B \NAC \NWC"3;
"S \NAC"
BN"12"24;
%"TAP"
"1","(400,3875)","2","standard","I271";
;
CDS_LIB"standard"
BODY_TYPE"PLUMBING"
HDL_TAP"TRUE";
"B \NAC \NWC"3;
"S \NAC"
BN"14"22;
%"TAP"
"1","(400,3825)","2","standard","I272";
;
CDS_LIB"standard"
BODY_TYPE"PLUMBING"
HDL_TAP"TRUE";
"B \NAC \NWC"3;
"S \NAC"
BN"13"23;
%"TAP"
"1","(400,3925)","2","standard","I273";
;
CDS_LIB"standard"
BODY_TYPE"PLUMBING"
HDL_TAP"TRUE";
"B \NAC \NWC"3;
"S \NAC"
BN"15"21;
%"TAP"
"1","(400,2475)","2","standard","I274";
;
CDS_LIB"standard"
BODY_TYPE"PLUMBING"
HDL_TAP"TRUE";
"B \NAC \NWC"4;
"S \NAC"
BN"3"17;
END.
